FILE_TYPE = CONNECTIVITY;
{Allegro Design Entry HDL 16.6-p007 (v16-6-112F) 10/10/2012}
"PAGE_NUMBER" = 139;
0"NC";
1"GND\g";
2"GND\g";
3"GND\g";
4"GND\g";
5"GND\g";
6"GND\g";
7"P1V5_LAN\g";
8"GND\g";
9"P0V9_LAN\g";
10"GND\g";
11"GND\g";
12"P3V3_STBY\g";
13"P3V3_STBY\g";
14"P3V3_STBY\g";
15"P3V3_STBY\g";
16"P3V3_STBY\g";
17"P3V3_STBY\g";
18"P3V3_STBY\g";
19"GND\g";
20"GND\g";
21"GND\g";
22"P0V9_LAN\g";
23"P1V5_LAN\g"VOLTAGE"+1.5V";
24"GND\g";
25"XTAL_25MHZ_IN_R";
26"XTAL_25MHZ_OUT";
27"IRQ_LOM_ALERT_N";
28"NIC_SER_P_MDI_3_DP";
29"NIC_SER_N_MDI_3_DN";
30"NIC_SET_P_MDI_2_DP";
31"NIC_SET_N_MDI_2_DN";
32"PU_SPRV_LAN_PWR_GOOD";
33"PD_SPRV_RSET";
34"SPI_NIC_CS_N";
35"RMII_SPRNGVLLE_BMC_PCH_RXD0";
36"RMII_PCH_SPRNGVLLE_ARB_IN";
37"PE_PCH_SPRV_RX_C_DN";
38"RMII_BMC_PCH_SPRNGVLLE_CRSDV";
39"RMII_BMC_PCH_SPRNGVLLE_TXEN";
40"PE_PCH_SPRV_RX_DN";
41"SPI_NIC_CS_R_N";
42"RMII_SPRNGVLLE_BMC_PCH_RXD0_R";
43"PU_JTAG_SPRV_TDO";
44"SPI_NIC_MOSI";
45"SPI_NIC_SCLK";
46"RMII_BMC_PCH_SPRNGVLLE_CRSDV";
47"RMII_SPRNGVLLE_BMC_PCH_RXD1";
48"PE_PCH_SPRV_RX_C_DP";
49"A_CTOP";
50"A_CBOT";
51"PE_PCH_SPRV_RX_DP";
52"TP_SPRV_SDP2";
53"TP_SPRV_SDP0";
54"SPI_NIC_SCLK_R";
55"SPI_NIC_MOSI_R";
56"RMII_SPRNGVLLE_BMC_PCH_RXD1_R";
57"RMII_BMC_PCH_SPRNGVLLE_CRSDV_R";
58"RMII_PCH_SPRNGVLLE_ARB_IN_R";
59"TP_SPRV_SDP3";
60"TP_SPRV_SDP1";
61"NIC_MDI_SPRV_RJ45_1_DP";
62"NIC_MDI_SPRV_RJ45_1_DN";
63"NIC_MDI_SPRV_RJ45_0_DN";
64"NIC_MDI_SPRV_RJ45_0_DP";
65"LED_LAN_2_N";
66"LED_LAN_1_N";
67"LED_LAN_0_N";
68"SMB_SPRINGVILLE_STBY_LVC3_SCL";
69"SMB_SPRINGVILLE_STBY_LVC3_SDA";
70"IRQ_LOM_ALERT_N";
71"CLK_50M_CKMNG_SPRVLLE";
72"NC_SPRNGVLLE_22";
73"P3V3_STBY_P1V5_LAN_I210"VOLTAGE"3.3";
74"PE_PCH_SPRV_TX_C_DN";
75"PE_PCH_SPRV_TX_C_DP";
76"P0V9_LAN_I210"VOLTAGE"0.9";
77"P1V5_LAN_I210"VOLTAGE"1.5";
78"FM_1GB_LOM_DISABLE_N";
79"PU_SPRV_LAN_PWR_GOOD";
80"PD_SPRV_RSET";
81"CLK_50M_CKMNG_SPRVLLE";
82"RMII_PCH_SPRNGVLLE_ARB_OUT";
83"RMII_BMC_PCH_SPRNGVLLE_TXEN";
84"PU_JTAG_SPRV_TMS";
85"PU_JTAG_SPRV_TDI";
86"PU_JTAG_SPRV_TCK";
87"SPI_NIC_MISO";
88"FM_PE_SPRV_WAKE_N";
89"RST_PLTRST_SPRV_R_N";
90"RST_PLTRST_SPRV_R_N";
91"RMII_BMC_PCH_SPRNGVLLE_TXD0";
92"RMII_BMC_PCH_SPRNGVLLE_TXD1";
93"PE_PCH_SPRV_TX_DN";
94"PE_PCH_SPRV_TX_DP";
95"CLK_100M_SPRV_DP";
96"CLK_100M_SPRV_DN";
97"XTAL_25MHZ_IN_R";
98"XTAL_25MHZ_OUT";
99"RST_PLTRST_N";
100"XTAL_25MHZ_IN";
101"XTAL_25MHZ_OUT_R";
%"CRYSTAL"
"1","(-7525,1475)","0","mstr_discrete","I109";
;
CDS_SEC"1"
BOM_COST"NT_GBE_BASE"
SEC_TYPE"2013"
SEC"1"
CDS_LOCATION"Y9E1"
ROOM"NIC_SPRV"
PACK_TYPE"2013"
CDS_LIB"mstr_discrete"
LOCATION"Y9E1"
VALUE"25.000MHZ"
MATERIAL"IC"
PART_NUMBER"D71700-057";
"B"
$PN"3"101;
"A"
$PN"1"100;
%"RES"
"1","(-6875,1675)","0","mstr_discrete","I110";
;
CDS_SEC"1"
PACK_TYPE"0402"
CDS_LIB"mstr_discrete"
SEC"1"
SEC_TYPE"0402"
BOM_COST"NT_GBE_BASE"
ROOM"NIC_SPRV"
PART_NUMBER"G21497-005"
CDS_LOCATION"R9E20"
WATTAGE"1/16W"
TOLERANCE"5%"
VALUE"0.0"
LOCATION"R9E20"
MATERIAL"CHIP";
"B"
$PN"2"97;
"A"
$PN"1"100;
%"CAP"
"1","(-7325,1275)","0","mstr_discrete","I111";
;
CDS_SEC"1"
SEC_TYPE"0402LF"
BOM_COST"NT_GBE_BASE"
SEC"1"
CDS_LOCATION"C9E8"
ROOM"NIC_SPRV"
CDS_LIB"mstr_discrete"
LOCATION"C9E8"
PART_NUMBER"A36095-030"
VALUE"22.0PF"
PACK_TYPE"0402LF"
VOLTAGE"50V"
TOLERANCE"5%"
MATERIAL"COG";
"A"
$PN"1"101;
"B"
$PN"2"1;
%"CAP"
"1","(-7750,1275)","0","mstr_discrete","I112";
;
CDS_SEC"1"
ROOM"NIC_SPRV"
SEC"1"
SEC_TYPE"0402LF"
BOM_COST"NT_GBE_BASE"
CDS_LOCATION"C9E9"
CDS_LIB"mstr_discrete"
LOCATION"C9E9"
PART_NUMBER"A36095-030"
VALUE"22.0PF"
TOLERANCE"5%"
PACK_TYPE"0402LF"
VOLTAGE"50V"
MATERIAL"COG";
"A"
$PN"1"100;
"B"
$PN"2"2;
%"GND"
"1","(-7325,925)","0","mstr_symbols","I113";
;
HDL_POWER"GND"
BODY_TYPE"PLUMBING"
CDS_LIB"mstr_symbols"
SIZE"1B"
VOLTAGE"0.0V";
"A\NAC"1;
%"GND"
"1","(-7750,925)","0","mstr_symbols","I114";
;
HDL_POWER"GND"
SIZE"1B"
VOLTAGE"0.0V"
CDS_LIB"mstr_symbols"
BODY_TYPE"PLUMBING";
"A\NAC"2;
%"RES"
"1","(-2425,2375)","0","mstr_discrete","I128";
;
CDS_SEC"1"
SEC_TYPE"0402"
SEC"1"
BOM_COST"NT_GBE_BASE"
CDS_LOCATION"R9E9"
PACK_TYPE"0402"
CDS_LIB"mstr_discrete"
ROOM"NIC_SPRV"
MATERIAL"CHIP"
WATTAGE"1/16W"
LOCATION"R9E9"
TOLERANCE"1%"
PART_NUMBER"G21796-074"
VALUE"33.2";
"B"
$PN"2"44;
"A"
$PN"1"55;
%"RES"
"1","(-1550,2325)","0","mstr_discrete","I129";
;
CDS_SEC"1"
CDS_LOCATION"R9E5"
PACK_TYPE"0402"
BOM_COST"NT_GBE_BASE"
SEC_TYPE"0402"
SEC"1"
CDS_LIB"mstr_discrete"
MATERIAL"CHIP"
ROOM"NIC_SPRV"
WATTAGE"1/16W"
TOLERANCE"1%"
LOCATION"R9E5"
VALUE"33.2"
PART_NUMBER"G21796-074";
"B"
$PN"2"34;
"A"
$PN"1"41;
%"RES"
"1","(-2400,2275)","0","mstr_discrete","I130";
;
CDS_SEC"1"
CDS_LOCATION"R9E8"
BOM_COST"NT_GBE_BASE"
ROOM"NIC_SPRV"
SEC_TYPE"0402"
SEC"1"
PACK_TYPE"0402"
CDS_LIB"mstr_discrete"
MATERIAL"CHIP"
LOCATION"R9E8"
WATTAGE"1/16W"
TOLERANCE"1%"
PART_NUMBER"G21796-074"
VALUE"33.2";
"B"
$PN"2"45;
"A"
$PN"1"54;
%"CAP"
"1","(-5975,4275)","0","mstr_discrete","I134";
;
CDS_SEC"1"
CDS_LOCATION"C1T4"
SEC"1"
SEC_TYPE"0603"
ROOM"NIC_SPRV"
BOM_COST"NT_GBE_BASE"
CDS_LIB"mstr_discrete"
LOCATION"C1T4"
PART_NUMBER"E15431-002"
VALUE"10UF"
TOLERANCE"20%"
VOLTAGE"6.3V"
MATERIAL"X6S"
PACK_TYPE"0603";
"A"
$PN"1"22;
"B"
$PN"2"5;
%"CAP"
"1","(-6325,3975)","0","mstr_discrete","I135";
;
CDS_SEC"1"
ROOM"NIC_SPRV"
SEC"1"
BOM_COST"NT_GBE_BASE"
SEC_TYPE"0603"
CDS_LOCATION"C1R30"
CDS_LIB"mstr_discrete"
PACK_TYPE"0603"
LOCATION"C1R30"
PART_NUMBER"E15431-002"
MATERIAL"X6S"
VOLTAGE"6.3V"
TOLERANCE"20%"
VALUE"10UF";
"A"
$PN"1"23;
"B"
$PN"2"4;
%"CAP"
"1","(-6725,3750)","0","mstr_discrete","I136";
;
CDS_SEC"1"
SEC_TYPE"0603"
BOM_COST"NT_GBE_BASE"
SEC"1"
ROOM"NIC_SPRV"
CDS_LOCATION"C1R22"
CDS_LIB"mstr_discrete"
TOLERANCE"20%"
VOLTAGE"6.3V"
LOCATION"C1R22"
PART_NUMBER"E15431-002"
VALUE"10UF"
PACK_TYPE"0603"
MATERIAL"X6S";
"A"
$PN"1"14;
"B"
$PN"2"3;
%"GND"
"1","(-6725,3500)","0","mstr_symbols","I137";
;
SIZE"1B"
HDL_POWER"GND"
VOLTAGE"0.0V"
CDS_LIB"mstr_symbols"
BODY_TYPE"PLUMBING";
"A\NAC"3;
%"GND"
"1","(-6325,3750)","0","mstr_symbols","I138";
;
HDL_POWER"GND"
VOLTAGE"0.0V"
CDS_LIB"mstr_symbols"
SIZE"1B"
BODY_TYPE"PLUMBING";
"A\NAC"4;
%"GND"
"1","(-5975,4050)","0","mstr_symbols","I139";
;
HDL_POWER"GND"
SIZE"1B"
CDS_LIB"mstr_symbols"
BODY_TYPE"PLUMBING"
VOLTAGE"0.0V";
"A\NAC"5;
%"CAP"
"1","(-5275,875)","0","mstr_discrete","I140";
;
$SEC"1"
ROOM"NIC_SPRV"
CDS_SEC"1"
BOM_COST"NT_GBE_BASE"
CDS_LOCATION"C9F2"
CDS_LIB"mstr_discrete"
MATERIAL"EMPTY"
LOCATION"C9F2"
PART_NUMBER"D38464-007"
VALUE"47UF"
PACK_TYPE"1210"
VOLTAGE"16V"
TOLERANCE"20%";
"A"
$PN"1"16;
"B"
$PN"2"6;
%"CAP"
"1","(-5025,875)","0","mstr_discrete","I142";
;
$SEC"1"
ROOM"NIC_SPRV"
CDS_SEC"1"
BOM_COST"NT_GBE_BASE"
CDS_LOCATION"C1R13"
CDS_LIB"mstr_discrete"
LOCATION"C1R13"
PART_NUMBER"E15431-002"
VALUE"10UF"
PACK_TYPE"0603"
VOLTAGE"6.3V"
MATERIAL"X6S"
TOLERANCE"20%";
"A"
$PN"1"16;
"B"
$PN"2"6;
%"CAP_A"
"1","(-4775,875)","0","dev_discrete","I143";
;
ROOM"NIC_SPRV"
BOM_COST"NT_GBE_BASE"
CDS_SEC"1"
$SEC"1"
CDS_LIB"dev_discrete"
CDS_LOCATION"C1R20"
LOCATION"C1R20"
PART_NUMBER"A36096-030"
VALUE"0.1UF"
PACK_TYPE"0402V"
MATERIAL"X7R"
VOLTAGE"16V"
TOLERANCE"10%";
"B"
$PN"2"6;
"A"
$PN"1"16;
%"CAP_A"
"1","(-4525,875)","0","dev_discrete","I144";
;
CDS_SEC"1"
$SEC"1"
BOM_COST"NT_GBE_BASE"
ROOM"NIC_SPRV"
CDS_LIB"dev_discrete"
CDS_LOCATION"C1T3"
PART_NUMBER"A36096-030"
VALUE"0.1UF"
PACK_TYPE"0402V"
MATERIAL"X7R"
VOLTAGE"16V"
TOLERANCE"10%"
LOCATION"C1T3";
"B"
$PN"2"6;
"A"
$PN"1"16;
%"CAP_A"
"1","(-4275,875)","0","dev_discrete","I145";
;
ROOM"NIC_SPRV"
BOM_COST"NT_GBE_BASE"
CDS_SEC"1"
$SEC"1"
CDS_LIB"dev_discrete"
CDS_LOCATION"C1R14"
LOCATION"C1R14"
PART_NUMBER"A36096-030"
VALUE"0.1UF"
PACK_TYPE"0402V"
MATERIAL"X7R"
VOLTAGE"16V"
TOLERANCE"10%";
"B"
$PN"2"6;
"A"
$PN"1"16;
%"CAP_A"
"1","(-4025,875)","0","dev_discrete","I146";
;
ROOM"NIC_SPRV"
BOM_COST"NT_GBE_BASE"
CDS_SEC"1"
$SEC"1"
CDS_LIB"dev_discrete"
CDS_LOCATION"C1R21"
LOCATION"C1R21"
PART_NUMBER"A36096-030"
VALUE"0.1UF"
PACK_TYPE"0402V"
MATERIAL"X7R"
VOLTAGE"16V"
TOLERANCE"10%";
"B"
$PN"2"6;
"A"
$PN"1"16;
%"GND"
"1","(-5275,575)","0","mstr_symbols","I147";
;
SIZE"1B"
HDL_POWER"GND"
VOLTAGE"0.0V"
CDS_LIB"mstr_symbols"
BODY_TYPE"PLUMBING";
"A\NAC"6;
%"CAP_A"
"1","(-2325,875)","0","dev_discrete","I149";
;
ROOM"NIC_SPRV"
BOM_COST"NT_GBE_BASE"
CDS_SEC"1"
$SEC"1"
CDS_LOCATION"C1R26"
CDS_LIB"dev_discrete"
PART_NUMBER"A36096-030"
LOCATION"C1R26"
VALUE"0.1UF"
TOLERANCE"10%"
PACK_TYPE"0402V"
VOLTAGE"16V"
MATERIAL"X7R";
"B"
$PN"2"8;
"A"
$PN"1"7;
%"CAP_A"
"1","(-2575,875)","0","dev_discrete","I150";
;
ROOM"NIC_SPRV"
BOM_COST"NT_GBE_BASE"
CDS_SEC"1"
$SEC"1"
CDS_LOCATION"C1R29"
CDS_LIB"dev_discrete"
PART_NUMBER"A36096-030"
MATERIAL"X7R"
VOLTAGE"16V"
TOLERANCE"10%"
VALUE"0.1UF"
LOCATION"C1R29"
PACK_TYPE"0402V";
"B"
$PN"2"8;
"A"
$PN"1"7;
%"CAP_A"
"1","(-2825,875)","0","dev_discrete","I151";
;
ROOM"NIC_SPRV"
BOM_COST"NT_GBE_BASE"
CDS_SEC"1"
$SEC"1"
CDS_LOCATION"C1R19"
CDS_LIB"dev_discrete"
PART_NUMBER"A36096-030"
MATERIAL"X7R"
VOLTAGE"16V"
TOLERANCE"10%"
VALUE"0.1UF"
LOCATION"C1R19"
PACK_TYPE"0402V";
"B"
$PN"2"8;
"A"
$PN"1"7;
%"CAP_A"
"1","(-3075,875)","0","dev_discrete","I152";
;
CDS_LOCATION"C1R31"
ROOM"NIC_SPRV"
BOM_COST"NT_GBE_BASE"
CDS_SEC"1"
$SEC"1"
CDS_LIB"dev_discrete"
PART_NUMBER"A36096-030"
MATERIAL"X7R"
VOLTAGE"16V"
TOLERANCE"10%"
VALUE"0.1UF"
LOCATION"C1R31"
PACK_TYPE"0402V";
"B"
$PN"2"8;
"A"
$PN"1"7;
%"CAP"
"1","(-3325,875)","0","mstr_discrete","I153";
;
ROOM"NIC_SPRV"
BOM_COST"NT_GBE_BASE"
CDS_SEC"1"
$SEC"1"
CDS_LIB"mstr_discrete"
CDS_LOCATION"C1R17"
PART_NUMBER"E15431-002"
VOLTAGE"6.3V"
MATERIAL"X6S"
LOCATION"C1R17"
VALUE"10UF"
TOLERANCE"20%"
PACK_TYPE"0603";
"A"
$PN"1"7;
"B"
$PN"2"8;
%"P1V5_LAN"
"1","(-3575,1175)","0","mstr_symbols","I154";
;
HDL_POWER"P1V5_LAN"
CDS_LIB"mstr_symbols"
VOLTAGE"1.5V"
BODY_TYPE"PLUMBING";
"G\NAC"7;
%"CAP"
"1","(-3575,875)","0","mstr_discrete","I155";
;
ROOM"NIC_SPRV"
$SEC"1"
CDS_SEC"1"
BOM_COST"NT_GBE_BASE"
CDS_LOCATION"C9E6"
CDS_LIB"mstr_discrete"
PART_NUMBER"D38464-007"
MATERIAL"EMPTY"
LOCATION"C9E6"
VALUE"47UF"
TOLERANCE"20%"
VOLTAGE"16V"
PACK_TYPE"1210";
"A"
$PN"1"7;
"B"
$PN"2"8;
%"GND"
"1","(-3575,575)","0","mstr_symbols","I156";
;
HDL_POWER"GND"
CDS_LIB"mstr_symbols"
SIZE"1B"
VOLTAGE"0.0V"
BODY_TYPE"PLUMBING";
"A\NAC"8;
%"CAP_A"
"1","(-350,875)","0","dev_discrete","I157";
;
ROOM"NIC_SPRV"
BOM_COST"NT_GBE_BASE"
CDS_SEC"1"
$SEC"1"
CDS_LOCATION"C1R18"
CDS_LIB"dev_discrete"
PACK_TYPE"0402V"
VOLTAGE"16V"
MATERIAL"X7R"
PART_NUMBER"A36096-030"
LOCATION"C1R18"
TOLERANCE"10%"
VALUE"0.1UF";
"B"
$PN"2"10;
"A"
$PN"1"9;
%"CAP_A"
"1","(-600,875)","0","dev_discrete","I158";
;
ROOM"NIC_SPRV"
BOM_COST"NT_GBE_BASE"
CDS_SEC"1"
$SEC"1"
CDS_LIB"dev_discrete"
CDS_LOCATION"C1T5"
LOCATION"C1T5"
PART_NUMBER"A36096-030"
VALUE"0.1UF"
TOLERANCE"10%"
PACK_TYPE"0402V"
VOLTAGE"16V"
MATERIAL"X7R";
"B"
$PN"2"10;
"A"
$PN"1"9;
%"CAP_A"
"1","(-850,875)","0","dev_discrete","I159";
;
$SEC"1"
CDS_SEC"1"
BOM_COST"NT_GBE_BASE"
ROOM"NIC_SPRV"
CDS_LIB"dev_discrete"
CDS_LOCATION"C1R24"
PART_NUMBER"A36096-030"
LOCATION"C1R24"
VALUE"0.1UF"
TOLERANCE"10%"
PACK_TYPE"0402V"
VOLTAGE"16V"
MATERIAL"X7R";
"B"
$PN"2"10;
"A"
$PN"1"9;
%"CAP_A"
"1","(-1100,875)","0","dev_discrete","I160";
;
$SEC"1"
CDS_SEC"1"
BOM_COST"NT_GBE_BASE"
ROOM"NIC_SPRV"
CDS_LIB"dev_discrete"
CDS_LOCATION"C1R15"
LOCATION"C1R15"
PART_NUMBER"A36096-030"
VALUE"0.1UF"
TOLERANCE"10%"
PACK_TYPE"0402V"
VOLTAGE"16V"
MATERIAL"X7R";
"B"
$PN"2"10;
"A"
$PN"1"9;
%"CAP"
"1","(-1350,875)","0","mstr_discrete","I161";
;
ROOM"NIC_SPRV"
$SEC"1"
CDS_SEC"1"
BOM_COST"NT_GBE_BASE"
CDS_LIB"mstr_discrete"
CDS_LOCATION"C1R16"
PART_NUMBER"E15431-002"
LOCATION"C1R16"
VALUE"10UF"
TOLERANCE"20%"
PACK_TYPE"0603"
VOLTAGE"6.3V"
MATERIAL"X6S";
"A"
$PN"1"9;
"B"
$PN"2"10;
%"P0V9_LAN"
"1","(-1925,1150)","0","mstr_symbols","I162";
;
HDL_POWER"P0V9_LAN"
BODY_TYPE"PLUMBING"
CDS_LIB"mstr_symbols"
VOLTAGE"0.9V";
"G\NAC"9;
%"CAP_A"
"1","(-1600,875)","0","dev_discrete","I163";
;
CDS_SEC"1"
BOM_COST"NT_GBE_BASE"
SEC"1"
SEC_TYPE"0603V"
ROOM"NIC_SPRV"
CDS_LOCATION"C9E1"
CDS_LIB"dev_discrete"
MATERIAL"EMPTY"
LOCATION"C9E1"
PART_NUMBER"E15431-004"
VALUE"22.0UF"
TOLERANCE"20%"
PACK_TYPE"0603V"
VOLTAGE"4V";
"B"
$PN"2"10;
"A"
$PN"1"9;
%"GND"
"1","(-1925,575)","0","mstr_symbols","I164";
;
SIZE"1B"
HDL_POWER"GND"
BODY_TYPE"PLUMBING"
CDS_LIB"mstr_symbols"
VOLTAGE"0.0V";
"A\NAC"10;
%"RES"
"2","(-900,3825)","0","mstr_discrete","I173";
;
CDS_SEC"1"
BOM_COST"NT_GBE_BASE"
$SEC"1"
CDS_LOCATION"R9F5"
ROOM"NIC_SPRV"
CDS_LIB"mstr_discrete"
LOCATION"R9F5"
PART_NUMBER"G21796-027"
VALUE"3.32K"
PACK_TYPE"0402"
MATERIAL"CHIP"
WATTAGE"1/16W"
TOLERANCE"1%";
"A"
$PN"1"15;
"B"
$PN"2"32;
%"RES"
"2","(-900,3225)","0","mstr_discrete","I174";
;
CDS_SEC"1"
SEC"1"
BOM_COST"NT_GBE_BASE"
SEC_TYPE"0402"
CDS_LOCATION"R9E23"
ROOM"NIC_SPRV"
CDS_LIB"mstr_discrete"
LOCATION"R9E23"
PART_NUMBER"G21796-013"
VALUE"4.99K"
MATERIAL"CHIP"
WATTAGE"1/16W"
TOLERANCE"1%"
PACK_TYPE"0402";
"A"
$PN"1"33;
"B"
$PN"2"11;
%"GND"
"1","(-900,2950)","0","mstr_symbols","I176";
;
HDL_POWER"GND"
VOLTAGE"0.0V"
CDS_LIB"mstr_symbols"
SIZE"1B"
BODY_TYPE"PLUMBING";
"A\NAC"11;
%"RES"
"2","(-7025,3125)","0","mstr_discrete","I177";
;
CDS_SEC"1"
BOM_COST"NT_GBE_BASE"
SEC_TYPE"0402"
SEC"1"
ROOM"NIC_SPRV"
CDS_LOCATION"R9E2"
CDS_LIB"mstr_discrete"
LOCATION"R9E2"
VALUE"10.0K"
WATTAGE"1/16W"
TOLERANCE"1%"
MATERIAL"CHIP"
PART_NUMBER"G21796-016"
PACK_TYPE"0402";
"A"
$PN"1"12;
"B"
$PN"2"86;
%"RES"
"2","(-7275,3125)","0","mstr_discrete","I178";
;
CDS_SEC"1"
BOM_COST"NT_GBE_BASE"
SEC_TYPE"0402"
SEC"1"
ROOM"NIC_SPRV"
CDS_LOCATION"R9E3"
CDS_LIB"mstr_discrete"
LOCATION"R9E3"
PART_NUMBER"G21796-016"
VALUE"10.0K"
PACK_TYPE"0402"
MATERIAL"CHIP"
WATTAGE"1/16W"
TOLERANCE"1%";
"A"
$PN"1"12;
"B"
$PN"2"84;
%"RES"
"2","(-7525,3125)","0","mstr_discrete","I179";
;
CDS_SEC"1"
SEC_TYPE"0402"
BOM_COST"NT_GBE_BASE"
SEC"1"
ROOM"NIC_SPRV"
CDS_LOCATION"R9E1"
CDS_LIB"mstr_discrete"
LOCATION"R9E1"
VALUE"10.0K"
TOLERANCE"1%"
WATTAGE"1/16W"
MATERIAL"CHIP"
PART_NUMBER"G21796-016"
PACK_TYPE"0402";
"A"
$PN"1"12;
"B"
$PN"2"85;
%"P3V3_STBY"
"1","(-7525,3450)","0","mstr_symbols","I180";
;
VOLTAGE"3.3V"
SIZE"1B"
CDS_LIB"mstr_symbols"
BODY_TYPE"PLUMBING"
HDL_POWER"P3V3_STBY";
"G\NAC"12;
%"RES"
"1","(-1500,2825)","0","mstr_discrete","I181";
;
CDS_SEC"1"
CDS_LOCATION"R9E22"
CDS_LIB"mstr_discrete"
SEC_TYPE"0402"
BOM_COST"NT_GBE_BASE"
SEC"1"
ROOM"NIC_SPRV"
PACK_TYPE"0402"
LOCATION"R9E22"
MATERIAL"CHIP"
VALUE"10.0K"
TOLERANCE"1%"
PART_NUMBER"G21796-016"
WATTAGE"1/16W";
"B"
$PN"2"13;
"A"
$PN"1"43;
%"P3V3_STBY"
"1","(-1175,3200)","0","mstr_symbols","I182";
;
VOLTAGE"3.3V"
SIZE"1B"
CDS_LIB"mstr_symbols"
BODY_TYPE"PLUMBING"
HDL_POWER"P3V3_STBY";
"G\NAC"13;
%"P3V3_STBY"
"1","(-6725,4000)","0","mstr_symbols","I186";
;
CDS_LIB"mstr_symbols"
SIZE"1B"
VOLTAGE"3.3V"
BODY_TYPE"PLUMBING"
HDL_POWER"P3V3_STBY";
"G\NAC"14;
%"P3V3_STBY"
"1","(-900,4050)","0","mstr_symbols","I188";
;
SIZE"1B"
BODY_TYPE"PLUMBING"
CDS_LIB"mstr_symbols"
VOLTAGE"3.3V"
HDL_POWER"P3V3_STBY";
"G\NAC"15;
%"P3V3_STBY"
"1","(-5275,1175)","0","mstr_symbols","I189";
;
SIZE"1B"
VOLTAGE"3.3V"
CDS_LIB"mstr_symbols"
BODY_TYPE"PLUMBING"
HDL_POWER"P3V3_STBY";
"G\NAC"16;
%"RES"
"2","(-1000,4475)","0","mstr_discrete","I193";
;
BOM_COST"NT_GBE_BASE"
CDS_SEC"1"
$SEC"1"
ROOM"NIC_SPRV"
CDS_LOCATION"R9E7"
CDS_LIB"mstr_discrete"
LOCATION"R9E7"
PART_NUMBER"G21796-027"
MATERIAL"CHIP"
VALUE"3.32K"
WATTAGE"1/16W"
TOLERANCE"1%"
PACK_TYPE"0402";
"A"
$PN"1"17;
"B"
$PN"2"27;
%"P3V3_STBY"
"1","(-1000,4700)","0","mstr_symbols","I194";
;
SIZE"1B"
CDS_LIB"mstr_symbols"
VOLTAGE"3.3V"
BODY_TYPE"PLUMBING"
HDL_POWER"P3V3_STBY";
"G\NAC"17;
%"RES"
"1","(-6600,550)","0","mstr_discrete","I195";
;
CDS_SEC"1"
SEC"1"
SEC_TYPE"0402"
CDS_LIB"mstr_discrete"
CDS_LOCATION"R1R1"
BOM_COST"NT_GBE_BASE"
ROOM"NIC_SPRV"
PART_NUMBER"G21497-005"
PACK_TYPE"0402"
WATTAGE"1/16W"
LOCATION"R1R1"
VALUE"0.0"
TOLERANCE"5%"
MATERIAL"CHIP";
"B"
$PN"2"89;
"A"
$PN"1"99;
%"P3V3_STBY"
"1","(-6350,1050)","0","mstr_symbols","I199";
;
SIZE"1B"
CDS_LIB"mstr_symbols"
BODY_TYPE"PLUMBING"
VOLTAGE"3.3V"
HDL_POWER"P3V3_STBY";
"G\NAC"18;
%"RES"
"2","(-6350,775)","0","mstr_discrete","I200";
;
CDS_SEC"1"
BOM_COST"NT_GBE_BASE"
SEC_TYPE"0402"
SEC"1"
ROOM"NIC_SPRV"
CDS_LOCATION"R9E4"
CDS_LIB"mstr_discrete"
PART_NUMBER"G21796-016"
TOLERANCE"1%"
LOCATION"R9E4"
VALUE"10.0K"
WATTAGE"1/16W"
MATERIAL"CHIP"
PACK_TYPE"0402";
"A"
$PN"1"18;
"B"
$PN"2"89;
%"RES"
"1","(-6875,1575)","0","mstr_discrete","I201";
;
CDS_SEC"1"
PACK_TYPE"0402"
CDS_LIB"mstr_discrete"
SEC"1"
SEC_TYPE"0402"
ROOM"NIC_SPRV"
CDS_LOCATION"R9E18"
BOM_COST"NT_GBE_BASE"
PART_NUMBER"G21497-005"
WATTAGE"1/16W"
TOLERANCE"5%"
LOCATION"R9E18"
VALUE"0.0"
MATERIAL"CHIP";
"B"
$PN"2"98;
"A"
$PN"1"101;
%"GND"
"1","(-1900,1375)","0","mstr_symbols","I204";
;
HDL_POWER"GND"
VOLTAGE"0.0V"
SIZE"1B"
CDS_LIB"mstr_symbols"
BODY_TYPE"PLUMBING";
"A\NAC"19;
%"GND"
"1","(-2875,1250)","0","mstr_symbols","I207";
;
SIZE"1B"
HDL_POWER"GND"
CDS_LIB"mstr_symbols"
VOLTAGE"0.0V"
BODY_TYPE"PLUMBING";
"A\NAC"20;
%"GND"
"1","(-875,1275)","0","mstr_symbols","I211";
;
HDL_POWER"GND"
CDS_LIB"mstr_symbols"
SIZE"1B"
BODY_TYPE"PLUMBING"
VOLTAGE"0.0V";
"A\NAC"21;
%"RES"
"2","(-1900,1650)","0","mstr_discrete","I212";
;
$SEC"1"
CDS_SEC"1"
BOM_COST"NT_GBE_BASE"
ROOM"NIC_SPRV"
CDS_LOCATION"R9E13"
CDS_LIB"mstr_discrete"
LOCATION"R9E13"
VALUE"10.0K"
MATERIAL"CHIP"
WATTAGE"1/16W"
TOLERANCE"1%"
PART_NUMBER"G21796-016"
PACK_TYPE"0402";
"A"
$PN"1"39;
"B"
$PN"2"19;
%"RES"
"2","(-2875,1525)","0","mstr_discrete","I213";
;
ROOM"NIC_SPRV"
CDS_LOCATION"R1R12"
$SEC"1"
CDS_SEC"1"
BOM_COST"NT_GBE_BASE"
CDS_LIB"mstr_discrete"
PART_NUMBER"G21796-016"
TOLERANCE"1%"
VALUE"10.0K"
LOCATION"R1R12"
PACK_TYPE"0402"
MATERIAL"CHIP"
WATTAGE"1/16W";
"A"
$PN"1"71;
"B"
$PN"2"20;
%"RES"
"2","(-875,1550)","0","mstr_discrete","I214";
;
BOM_COST"NT_GBE_BASE"
CDS_SEC"1"
$SEC"1"
CDS_LOCATION"R1T1"
ROOM"NIC_SPRV"
CDS_LIB"mstr_discrete"
LOCATION"R1T1"
VALUE"10.0K"
TOLERANCE"1%"
WATTAGE"1/16W"
MATERIAL"CHIP"
PACK_TYPE"0402"
PART_NUMBER"G21796-016";
"A"
$PN"1"38;
"B"
$PN"2"21;
%"RES"
"1","(-2400,2675)","0","mstr_discrete","I225";
;
CDS_SEC"1"
$SEC"1"
CDS_LIB"mstr_discrete"
CDS_LOCATION"R9F1"
PACK_TYPE"0402"
WATTAGE"1/16W"
LOCATION"R9F1"
TOLERANCE"1.0%"
VALUE"22.1"
PART_NUMBER"G21796-250"
MATERIAL"CHIP";
"B"
$PN"2"46;
"A"
$PN"1"57;
%"RES"
"1","(-2275,2525)","0","mstr_discrete","I228";
;
CDS_SEC"1"
BOM_COST"SM_CONTROLLER"
ROOM"BMC"
PACK_TYPE"0402"
SEC"1"
SEC_TYPE"0402"
PART_NUMBER"G21796-250"
CDS_LIB"mstr_discrete"
WATTAGE"1/16W"
CDS_LOCATION"R9E19"
VALUE"22.1"
TOLERANCE"1.0%"
LOCATION"R9E19"
MATERIAL"CHIP";
"B"
$PN"2"47;
"A"
$PN"1"56;
%"RES"
"1","(-1750,2475)","0","mstr_discrete","I229";
;
CDS_SEC"1"
BOM_COST"SM_CONTROLLER"
ROOM"BMC"
PACK_TYPE"0402"
PART_NUMBER"G21796-250"
SEC_TYPE"0402"
SEC"1"
WATTAGE"1/16W"
CDS_LIB"mstr_discrete"
CDS_LOCATION"R9E17"
VALUE"22.1"
TOLERANCE"1.0%"
LOCATION"R9E17"
MATERIAL"CHIP";
"B"
$PN"2"35;
"A"
$PN"1"42;
%"RES"
"1","(-2075,2725)","0","mstr_discrete","I235";
;
CDS_SEC"1"
ROOM"SB"
PACK_TYPE"0402"
CDS_LOCATION"R9E16"
SEC_TYPE"0402"
SEC"1"
CDS_LIB"mstr_discrete"
WATTAGE"1/16W"
MATERIAL"CHIP"
PART_NUMBER"G21796-074"
LOCATION"R9E16"
TOLERANCE"1%"
VALUE"33.2";
"B"
$PN"2"36;
"A"
$PN"1"58;
%"RES"
"1","(-5600,4025)","0","mstr_discrete","I237";
;
CDS_SEC"1"
BOM_COST"NT_GBE_BASE"
ROOM"NIC_SPRV"
SEC_TYPE"0603"
SEC"1"
CDS_LOCATION"R1R15"
CDS_LIB"mstr_discrete"
WATTAGE"1/10W"
MATERIAL"CHIP"
TOLERANCE"5.0%"
LOCATION"R1R15"
PACK_TYPE"0603"
VALUE"0"
PART_NUMBER"G22178-002";
"B"
$PN"2"76;
"A"
$PN"1"22;
%"RES"
"1","(-5800,3875)","0","mstr_discrete","I238";
;
CDS_SEC"1"
BOM_COST"NT_GBE_BASE"
SEC_TYPE"0603"
SEC"1"
ROOM"NIC_SPRV"
CDS_LOCATION"R1T32"
CDS_LIB"mstr_discrete"
TOLERANCE"5.0%"
MATERIAL"CHIP"
WATTAGE"1/10W"
LOCATION"R1T32"
PACK_TYPE"0603"
VALUE"0"
PART_NUMBER"G22178-002";
"B"
$PN"2"77;
"A"
$PN"1"23;
%"RES"
"1","(-5600,3525)","0","mstr_discrete","I239";
;
CDS_SEC"1"
BOM_COST"NT_GBE_BASE"
ROOM"NIC_SPRV"
CDS_LOCATION"R1T34"
CDS_LIB"mstr_discrete"
WATTAGE"1/10W"
MATERIAL"CHIP"
TOLERANCE"5.0%"
SEC_TYPE"0603"
SEC"1"
PACK_TYPE"0603"
LOCATION"R1T34"
VALUE"0"
PART_NUMBER"G22178-002";
"B"
$PN"2"73;
"A"
$PN"1"14;
%"RES"
"1","(-5800,3725)","0","mstr_discrete","I240";
;
CDS_SEC"1"
BOM_COST"NT_GBE_BASE"
ROOM"NIC_SPRV"
SEC_TYPE"0603"
SEC"1"
CDS_LOCATION"R1T33"
CDS_LIB"mstr_discrete"
TOLERANCE"5.0%"
WATTAGE"1/10W"
LOCATION"R1T33"
PACK_TYPE"0603"
VALUE"0"
MATERIAL"EMPTY"
PART_NUMBER"G22178-002";
"B"
$PN"2"73;
"A"
$PN"1"23;
%"CAP_A"
"1","(-1925,875)","0","dev_discrete","I241";
;
CDS_SEC"1"
CDS_LOCATION"C9E12"
ROOM"NIC_SPRV"
SEC_TYPE"0603V"
SEC"1"
BOM_COST"NT_GBE_BASE"
CDS_LIB"dev_discrete"
MATERIAL"EMPTY"
LOCATION"C9E12"
PART_NUMBER"E15431-004"
VALUE"22.0UF"
TOLERANCE"20%"
PACK_TYPE"0603V"
VOLTAGE"4V";
"B"
$PN"2"10;
"A"
$PN"1"9;
%"SPRINGVILLE"
"2","(-4200,3125)","0","mstr_intel","I72";
;
CDS_SEC"1"
BOM_COST"NT_GBE_BASE"
ROOM"NIC_SPRV"
SEC_TYPE"SM1"
PACK_TYPE"SM1"
CDS_LOCATION"EU9E1"
SEC"1"
CDS_LIB"mstr_intel"
MATERIAL"IC"
LOCATION"EU9E1"
PART_NUMBER"G47144-004";
"VDD1P5<0>"
$PN"56"77;
"VDD1P5_OUT"
$PN"39"23;
"VDD1P5<1>"
$PN"47"23;
"VDD0P9_OUT"
$PN"38"76;
"VDD0P9<0>"
$PN"59"22;
"VDD0P9<1>"
$PN"32"22;
"VDD0P9<2>"
$PN"11"22;
"VDD0P9<3>"
$PN"42"22;
"XTAL2"
$PN"45"26;
"XTAL1"
$PN"46"25;
"VDD3P3<3>"
$PN"27"14;
"VDD3P3<4>"
$PN"10"14;
"SMB_CLK"
$PN"34"68;
"SDP2"
$PN"62"52;
"SDP0"
$PN"63"53;
"RSET"
$PN"48"80;
"PE_WAKE_N"
$PN"16"88;
"PE_TP"
$PN"21"51;
"PE_TN"
$PN"20"40;
"PE_RST_N"
$PN"17"90;
"PE_RP"
$PN"24"75;
"PE_RN"
$PN"23"74;
"PECLKP"
$PN"26"95;
"PECLKN"
$PN"25"96;
"NVM_SO"
$PN"14"87;
"NVM_SK"
$PN"13"54;
"NVM_SI"
$PN"12"55;
"NVM_CS_N"
$PN"15"41;
"NC_SI_TX_EN"
$PN"7"83;
"NC_SI_TXD1"
$PN"8"92;
"NC_SI_TXD0"
$PN"9"91;
"NC_SI_RXD1"
$PN"5"56;
"NC_SI_RXD0"
$PN"6"42;
"NC_SI_CRS_DV"
$PN"3"57;
"NC_SI_CLK_IN"
$PN"2"81;
"NC_SI_ARB_OUT"
$PN"44"58;
"NC_SI_ARB_IN"
$PN"43"82;
"NC"
$PN"22"72;
"LED2"
$PN"33"65;
"LED1"
$PN"30"66;
"LED0"
$PN"31"67;
"LAN_PWR_GOOD"
$PN"1"79;
"JTAG_TMS"
$PN"18"84;
"JTAG_TDI"
$PN"29"85;
"JTAG_CLK"
$PN"19"86;
"GND"
$PN"65"24;
"DEV_OFF_N"
$PN"28"78;
"CTOP"
$PN"40"49;
"CBOT"
$PN"37"50;
"MDI_PLUS3_SERP"
$PN"50"28;
"MDI_MINUS3_SERN"
$PN"49"29;
"MDI_PLUS2_SETP"
$PN"53"30;
"MDI_MINUS2_SETN"
$PN"52"31;
"MDI_PLUS1_SFP_I2C_CLK"
$PN"55"61;
"MDI_MINUS1_SRDS_SIG_DET"
$PN"54"62;
"MDI_MINUS0_SFP_I2C_DATA"
$PN"57"63;
"MDI_PLUS0_NC"
$PN"58"64;
"SDP3"
$PN"60"59;
"SDP1_PCIE_DIS_SDP1"
$PN"61"60;
"JTAG_TDO"
$PN"4"43;
"SMB_ALRT_N"
$PN"35"70;
"SMB_DATA"
$PN"36"69;
"VDD3P3<0>"
$PN"64"14;
"VDD3P3<1>"
$PN"51"73;
"VDD3P3<2>"
$PN"41"14;
%"P0V9_LAN"
"1","(-5725,4525)","0","mstr_symbols","I73";
;
HDL_POWER"P0V9_LAN"
CDS_LIB"mstr_symbols"
VOLTAGE"0.9V"
BODY_TYPE"PLUMBING";
"G\NAC"22;
%"P1V5_LAN"
"1","(-6325,4300)","0","mstr_symbols","I74";
;
HDL_POWER"P1V5_LAN"
BODY_TYPE"PLUMBING"
CDS_LIB"mstr_symbols"
VOLTAGE"1.5V";
"G\NAC"23;
%"CAP"
"1","(-2725,3500)","0","mstr_discrete","I76";
;
CDS_SEC"1"
SEC_TYPE"0402LF"
BOM_COST"NT_GBE_BASE"
SEC"1"
CDS_LOCATION"C9E7"
ROOM"NIC_SPRV"
CDS_LIB"mstr_discrete"
LOCATION"C9E7"
VALUE"0.039UF"
MATERIAL"X7R"
VOLTAGE"25V"
TOLERANCE"10%"
PACK_TYPE"0402LF"
PART_NUMBER"A36096-063";
"A"
$PN"1"49;
"B"
$PN"2"50;
%"GND"
"1","(-3175,1425)","0","mstr_symbols","I77";
;
HDL_POWER"GND"
SIZE"1B"
CDS_LIB"mstr_symbols"
BODY_TYPE"PLUMBING"
VOLTAGE"0.0V";
"A\NAC"24;
%"CAP_A"
"2","(-1650,2075)","0","dev_discrete","I87";
;
CDS_LOCATION"C9E5"
CDS_SEC"1"
SEC_TYPE"0402V"
SEC"1"
BOM_COST"NT_GBE_BASE"
ROOM"NIC_SPRV"
CDS_LIB"dev_discrete"
LOCATION"C9E5"
PART_NUMBER"A36096-030"
MATERIAL"X7R"
VOLTAGE"16V"
PACK_TYPE"0402V"
TOLERANCE"10%"
VALUE"0.1UF";
"A"
$PN"1"40;
"B"
$PN"2"37;
%"CAP_A"
"2","(-2400,2125)","0","dev_discrete","I88";
;
CDS_SEC"1"
CDS_LOCATION"C9E4"
SEC_TYPE"0402V"
SEC"1"
BOM_COST"NT_GBE_BASE"
ROOM"NIC_SPRV"
CDS_LIB"dev_discrete"
LOCATION"C9E4"
PART_NUMBER"A36096-030"
VALUE"0.1UF"
VOLTAGE"16V"
TOLERANCE"10%"
PACK_TYPE"0402V"
MATERIAL"X7R";
"A"
$PN"1"51;
"B"
$PN"2"48;
%"CAP_A"
"2","(-5775,2125)","0","dev_discrete","I89";
;
SEC"1"
SEC_TYPE"0402V"
BOM_COST"NT_GBE_BASE"
ROOM"NIC_SPRV"
CDS_SEC"1"
CDS_LIB"dev_discrete"
CDS_LOCATION"C2M23"
PART_NUMBER"A36096-030"
LOCATION"C2M23"
VALUE"0.1UF"
VOLTAGE"16V"
MATERIAL"X7R"
PACK_TYPE"0402V"
TOLERANCE"10%";
"A"
$PN"1"94;
"B"
$PN"2"75;
%"CAP_A"
"2","(-6000,2075)","0","dev_discrete","I90";
;
SEC_TYPE"0402V"
SEC"1"
BOM_COST"NT_GBE_BASE"
CDS_SEC"1"
CDS_LIB"dev_discrete"
CDS_LOCATION"C2M24"
ROOM"NIC_SPRV"
LOCATION"C2M24"
VOLTAGE"16V"
MATERIAL"X7R"
PACK_TYPE"0402V"
TOLERANCE"10%"
PART_NUMBER"A36096-030"
VALUE"0.1UF";
"A"
$PN"1"93;
"B"
$PN"2"74;
END.
